(kicad_pcb
	(version 20260206)
	(generator "pcbnew")
	(generator_version "10.0")
	(general
		(thickness 1.6)
		(legacy_teardrops no)
	)
	(paper "A4")
	(title_block
		(title "04192023_DAF0TMB3IC0_F0TG_MB_C_brd_V02_OCP.brd")
		(comment 1 "Grand Teton / footprints 7741-7746 of 8354")
	)
	(layers
		(0 "F.Cu" signal "TOP")
		(4 "In1.Cu" signal "GND")
		(6 "In2.Cu" signal "IN1")
		(8 "In3.Cu" signal "GND1")
		(10 "In4.Cu" signal "IN2")
		(12 "In5.Cu" signal "GND2")
		(14 "In6.Cu" signal "IN3")
		(16 "In7.Cu" signal "GND3")
		(18 "In8.Cu" signal "VCC")
		(20 "In9.Cu" signal "VCC1")
		(22 "In10.Cu" signal "GND4")
		(24 "In11.Cu" signal "IN4")
		(26 "In12.Cu" signal "GND5")
		(28 "In13.Cu" signal "IN5")
		(30 "In14.Cu" signal "GND6")
		(32 "In15.Cu" signal "IN6")
		(34 "In16.Cu" signal "GND7")
		(2 "B.Cu" signal "BOTTOM")
		(9 "F.Adhes" user "F.Adhesive")
		(11 "B.Adhes" user "B.Adhesive")
		(13 "F.Paste" user "Package Geometry/Pastemask Top")
		(15 "B.Paste" user "Package Geometry/Pastemask Bottom")
		(5 "F.SilkS" user "Ref Des/Silkscreen Top")
		(7 "B.SilkS" user "Ref Des/Silkscreen Bottom")
		(1 "F.Mask" user "Board Geometry/Soldermask Top")
		(3 "B.Mask" user "Board Geometry/Soldermask Bottom")
		(17 "Dwgs.User" user "User.Drawings")
		(19 "Cmts.User" user "User.Comments")
		(21 "Eco1.User" user "User.Eco1")
		(23 "Eco2.User" user "User.Eco2")
		(25 "Edge.Cuts" user "Board Geometry/Outline")
		(27 "Margin" user)
		(31 "F.CrtYd" user "Package Geometry/Place Bound Top")
		(29 "B.CrtYd" user "Package Geometry/Place Bound Bottom")
		(35 "F.Fab" user "Ref Des/Assembly Top")
		(33 "B.Fab" user "Ref Des/Assembly Bottom")
	)
	(footprint ""
		(layer "B.Cu")
		(at 62.991238 -390.560052 90)
		(property "Reference" "C284"
			(at 0 0 90)
			(layer "B.SilkS")
			(hide yes)
			(effects
				(font
					(size 1.27 1.27)
				)
				(justify mirror)
			)
		)
		(property "Value" ""
			(at 0 0 90)
			(layer "B.Fab")
			(effects
				(font
					(size 1.27 1.27)
				)
				(justify mirror)
			)
		)
		(duplicate_pad_numbers_are_jumpers no)
		(fp_line
			(start 0.7874 -0.4064)
			(end -0.7874 -0.4064)
			(stroke
				(width 0.1524)
				(type default)
			)
			(layer "B.SilkS")
		)
		(fp_line
			(start -0.7874 -0.4064)
			(end -0.7874 0.4064)
			(stroke
				(width 0.1524)
				(type default)
			)
			(layer "B.SilkS")
		)
		(fp_line
			(start 0.7874 0.4064)
			(end 0.7874 -0.4064)
			(stroke
				(width 0.1524)
				(type default)
			)
			(layer "B.SilkS")
		)
		(fp_line
			(start -0.7874 0.4064)
			(end 0.7874 0.4064)
			(stroke
				(width 0.1524)
				(type default)
			)
			(layer "B.SilkS")
		)
		(fp_line
			(start 0.67945 -0.305054)
			(end 0.12065 -0.305054)
			(stroke
				(width 0.1)
				(type default)
			)
			(layer "B.Fab")
		)
		(fp_line
			(start 0.12065 -0.305054)
			(end 0.12065 -0.2794)
			(stroke
				(width 0.1)
				(type default)
			)
			(layer "B.Fab")
		)
		(fp_line
			(start -0.12065 -0.3048)
			(end -0.67945 -0.3048)
			(stroke
				(width 0.1)
				(type default)
			)
			(layer "B.Fab")
		)
		(fp_line
			(start -0.67945 -0.3048)
			(end -0.67945 0.3048)
			(stroke
				(width 0.1)
				(type default)
			)
			(layer "B.Fab")
		)
		(fp_line
			(start 0.12065 -0.2794)
			(end -0.12065 -0.2794)
			(stroke
				(width 0.1)
				(type default)
			)
			(layer "B.Fab")
		)
		(fp_line
			(start -0.12065 -0.2794)
			(end -0.12065 -0.3048)
			(stroke
				(width 0.1)
				(type default)
			)
			(layer "B.Fab")
		)
		(fp_line
			(start 0.12065 0.2794)
			(end 0.12065 0.3048)
			(stroke
				(width 0.1)
				(type default)
			)
			(layer "B.Fab")
		)
		(fp_line
			(start -0.120396 0.2794)
			(end 0.12065 0.2794)
			(stroke
				(width 0.1)
				(type default)
			)
			(layer "B.Fab")
		)
		(fp_line
			(start 0.67945 0.3048)
			(end 0.67945 -0.305054)
			(stroke
				(width 0.1)
				(type default)
			)
			(layer "B.Fab")
		)
		(fp_line
			(start 0.12065 0.3048)
			(end 0.67945 0.3048)
			(stroke
				(width 0.1)
				(type default)
			)
			(layer "B.Fab")
		)
		(fp_line
			(start -0.120396 0.3048)
			(end -0.120396 0.2794)
			(stroke
				(width 0.1)
				(type default)
			)
			(layer "B.Fab")
		)
		(fp_line
			(start -0.67945 0.3048)
			(end -0.120396 0.3048)
			(stroke
				(width 0.1)
				(type default)
			)
			(layer "B.Fab")
		)
		(pad "1" smd circle
			(at 0.40005 0 270)
			(size 0 0)
			(layers "B.Cu" "B.Mask" "B.Paste")
			(net "P0V9_CPU1_RT0_2A")
		)
		(pad "2" smd circle
			(at -0.40005 0 270)
			(size 0 0)
			(layers "B.Cu" "B.Mask" "B.Paste")
			(net "GND")
		)
	)
	(footprint ""
		(layer "B.Cu")
		(at 242.951 -228.092 -90)
		(property "Reference" "R1153"
			(at 0 0 90)
			(layer "B.SilkS")
			(hide yes)
			(effects
				(font
					(size 1.27 1.27)
				)
				(justify mirror)
			)
		)
		(property "Value" ""
			(at 0 0 90)
			(layer "B.Fab")
			(effects
				(font
					(size 1.27 1.27)
				)
				(justify mirror)
			)
		)
		(duplicate_pad_numbers_are_jumpers no)
		(fp_line
			(start -0.7874 0.4064)
			(end 0.7874 0.4064)
			(stroke
				(width 0.1524)
				(type default)
			)
			(layer "B.SilkS")
		)
		(fp_line
			(start 0.7874 0.4064)
			(end 0.7874 -0.4064)
			(stroke
				(width 0.1524)
				(type default)
			)
			(layer "B.SilkS")
		)
		(fp_line
			(start -0.7874 -0.4064)
			(end -0.7874 0.4064)
			(stroke
				(width 0.1524)
				(type default)
			)
			(layer "B.SilkS")
		)
		(fp_line
			(start 0.7874 -0.4064)
			(end -0.7874 -0.4064)
			(stroke
				(width 0.1524)
				(type default)
			)
			(layer "B.SilkS")
		)
		(fp_line
			(start -0.67945 0.3048)
			(end -0.120396 0.3048)
			(stroke
				(width 0.1)
				(type default)
			)
			(layer "B.Fab")
		)
		(fp_line
			(start -0.120396 0.3048)
			(end -0.120396 0.2794)
			(stroke
				(width 0.1)
				(type default)
			)
			(layer "B.Fab")
		)
		(fp_line
			(start 0.12065 0.3048)
			(end 0.67945 0.3048)
			(stroke
				(width 0.1)
				(type default)
			)
			(layer "B.Fab")
		)
		(fp_line
			(start 0.67945 0.3048)
			(end 0.67945 -0.305054)
			(stroke
				(width 0.1)
				(type default)
			)
			(layer "B.Fab")
		)
		(fp_line
			(start -0.120396 0.2794)
			(end 0.12065 0.2794)
			(stroke
				(width 0.1)
				(type default)
			)
			(layer "B.Fab")
		)
		(fp_line
			(start 0.12065 0.2794)
			(end 0.12065 0.3048)
			(stroke
				(width 0.1)
				(type default)
			)
			(layer "B.Fab")
		)
		(fp_line
			(start -0.12065 -0.2794)
			(end -0.12065 -0.3048)
			(stroke
				(width 0.1)
				(type default)
			)
			(layer "B.Fab")
		)
		(fp_line
			(start 0.12065 -0.2794)
			(end -0.12065 -0.2794)
			(stroke
				(width 0.1)
				(type default)
			)
			(layer "B.Fab")
		)
		(fp_line
			(start -0.67945 -0.3048)
			(end -0.67945 0.3048)
			(stroke
				(width 0.1)
				(type default)
			)
			(layer "B.Fab")
		)
		(fp_line
			(start -0.12065 -0.3048)
			(end -0.67945 -0.3048)
			(stroke
				(width 0.1)
				(type default)
			)
			(layer "B.Fab")
		)
		(fp_line
			(start 0.12065 -0.305054)
			(end 0.12065 -0.2794)
			(stroke
				(width 0.1)
				(type default)
			)
			(layer "B.Fab")
		)
		(fp_line
			(start 0.67945 -0.305054)
			(end 0.12065 -0.305054)
			(stroke
				(width 0.1)
				(type default)
			)
			(layer "B.Fab")
		)
		(pad "1" smd circle
			(at 0.40005 0 90)
			(size 0 0)
			(layers "B.Cu" "B.Mask" "B.Paste")
			(net "SMB_CPU0_CPU1_SEC_SCL_R1")
		)
		(pad "2" smd circle
			(at -0.40005 0 90)
			(size 0 0)
			(layers "B.Cu" "B.Mask" "B.Paste")
			(net "SMB_CPU0_CPU1_SEC_SCL_R2")
		)
	)
	(footprint ""
		(layer "B.Cu")
		(at 186.817 -100.294948 -90)
		(property "Reference" "R181"
			(at 0 0 90)
			(layer "B.SilkS")
			(hide yes)
			(effects
				(font
					(size 1.27 1.27)
				)
				(justify mirror)
			)
		)
		(property "Value" ""
			(at 0 0 90)
			(layer "B.Fab")
			(effects
				(font
					(size 1.27 1.27)
				)
				(justify mirror)
			)
		)
		(duplicate_pad_numbers_are_jumpers no)
		(fp_line
			(start -0.7874 0.4064)
			(end 0.7874 0.4064)
			(stroke
				(width 0.1524)
				(type default)
			)
			(layer "B.SilkS")
		)
		(fp_line
			(start 0.7874 0.4064)
			(end 0.7874 -0.4064)
			(stroke
				(width 0.1524)
				(type default)
			)
			(layer "B.SilkS")
		)
		(fp_line
			(start -0.7874 -0.4064)
			(end -0.7874 0.4064)
			(stroke
				(width 0.1524)
				(type default)
			)
			(layer "B.SilkS")
		)
		(fp_line
			(start 0.7874 -0.4064)
			(end -0.7874 -0.4064)
			(stroke
				(width 0.1524)
				(type default)
			)
			(layer "B.SilkS")
		)
		(fp_line
			(start -0.67945 0.3048)
			(end -0.120396 0.3048)
			(stroke
				(width 0.1)
				(type default)
			)
			(layer "B.Fab")
		)
		(fp_line
			(start -0.120396 0.3048)
			(end -0.120396 0.2794)
			(stroke
				(width 0.1)
				(type default)
			)
			(layer "B.Fab")
		)
		(fp_line
			(start 0.12065 0.3048)
			(end 0.67945 0.3048)
			(stroke
				(width 0.1)
				(type default)
			)
			(layer "B.Fab")
		)
		(fp_line
			(start 0.67945 0.3048)
			(end 0.67945 -0.305054)
			(stroke
				(width 0.1)
				(type default)
			)
			(layer "B.Fab")
		)
		(fp_line
			(start -0.120396 0.2794)
			(end 0.12065 0.2794)
			(stroke
				(width 0.1)
				(type default)
			)
			(layer "B.Fab")
		)
		(fp_line
			(start 0.12065 0.2794)
			(end 0.12065 0.3048)
			(stroke
				(width 0.1)
				(type default)
			)
			(layer "B.Fab")
		)
		(fp_line
			(start -0.12065 -0.2794)
			(end -0.12065 -0.3048)
			(stroke
				(width 0.1)
				(type default)
			)
			(layer "B.Fab")
		)
		(fp_line
			(start 0.12065 -0.2794)
			(end -0.12065 -0.2794)
			(stroke
				(width 0.1)
				(type default)
			)
			(layer "B.Fab")
		)
		(fp_line
			(start -0.67945 -0.3048)
			(end -0.67945 0.3048)
			(stroke
				(width 0.1)
				(type default)
			)
			(layer "B.Fab")
		)
		(fp_line
			(start -0.12065 -0.3048)
			(end -0.67945 -0.3048)
			(stroke
				(width 0.1)
				(type default)
			)
			(layer "B.Fab")
		)
		(fp_line
			(start 0.12065 -0.305054)
			(end 0.12065 -0.2794)
			(stroke
				(width 0.1)
				(type default)
			)
			(layer "B.Fab")
		)
		(fp_line
			(start 0.67945 -0.305054)
			(end 0.12065 -0.305054)
			(stroke
				(width 0.1)
				(type default)
			)
			(layer "B.Fab")
		)
		(pad "1" smd circle
			(at 0.40005 0 90)
			(size 0 0)
			(layers "B.Cu" "B.Mask" "B.Paste")
			(net "CPU0_SP5R2")
		)
		(pad "2" smd circle
			(at -0.40005 0 90)
			(size 0 0)
			(layers "B.Cu" "B.Mask" "B.Paste")
			(net "FM_CPU0_SP5R2")
		)
	)
	(footprint ""
		(layer "B.Cu")
		(at 158.39948 -352.566478 180)
		(property "Reference" "R8385"
			(at 0 0 0)
			(layer "B.SilkS")
			(hide yes)
			(effects
				(font
					(size 1.27 1.27)
				)
				(justify mirror)
			)
		)
		(property "Value" ""
			(at 0 0 0)
			(layer "B.Fab")
			(effects
				(font
					(size 1.27 1.27)
				)
				(justify mirror)
			)
		)
		(duplicate_pad_numbers_are_jumpers no)
		(fp_line
			(start 0.7874 0.4064)
			(end 0.7874 -0.4064)
			(stroke
				(width 0.1524)
				(type default)
			)
			(layer "B.SilkS")
		)
		(fp_line
			(start 0.7874 -0.4064)
			(end -0.7874 -0.4064)
			(stroke
				(width 0.1524)
				(type default)
			)
			(layer "B.SilkS")
		)
		(fp_line
			(start -0.7874 0.4064)
			(end 0.7874 0.4064)
			(stroke
				(width 0.1524)
				(type default)
			)
			(layer "B.SilkS")
		)
		(fp_line
			(start -0.7874 -0.4064)
			(end -0.7874 0.4064)
			(stroke
				(width 0.1524)
				(type default)
			)
			(layer "B.SilkS")
		)
		(fp_line
			(start 0.67945 0.3048)
			(end 0.67945 -0.305054)
			(stroke
				(width 0.1)
				(type default)
			)
			(layer "B.Fab")
		)
		(fp_line
			(start 0.67945 -0.305054)
			(end 0.12065 -0.305054)
			(stroke
				(width 0.1)
				(type default)
			)
			(layer "B.Fab")
		)
		(fp_line
			(start 0.12065 0.3048)
			(end 0.67945 0.3048)
			(stroke
				(width 0.1)
				(type default)
			)
			(layer "B.Fab")
		)
		(fp_line
			(start 0.12065 0.2794)
			(end 0.12065 0.3048)
			(stroke
				(width 0.1)
				(type default)
			)
			(layer "B.Fab")
		)
		(fp_line
			(start 0.12065 -0.2794)
			(end -0.12065 -0.2794)
			(stroke
				(width 0.1)
				(type default)
			)
			(layer "B.Fab")
		)
		(fp_line
			(start 0.12065 -0.305054)
			(end 0.12065 -0.2794)
			(stroke
				(width 0.1)
				(type default)
			)
			(layer "B.Fab")
		)
		(fp_line
			(start -0.120396 0.3048)
			(end -0.120396 0.2794)
			(stroke
				(width 0.1)
				(type default)
			)
			(layer "B.Fab")
		)
		(fp_line
			(start -0.120396 0.2794)
			(end 0.12065 0.2794)
			(stroke
				(width 0.1)
				(type default)
			)
			(layer "B.Fab")
		)
		(fp_line
			(start -0.12065 -0.2794)
			(end -0.12065 -0.3048)
			(stroke
				(width 0.1)
				(type default)
			)
			(layer "B.Fab")
		)
		(fp_line
			(start -0.12065 -0.3048)
			(end -0.67945 -0.3048)
			(stroke
				(width 0.1)
				(type default)
			)
			(layer "B.Fab")
		)
		(fp_line
			(start -0.67945 0.3048)
			(end -0.120396 0.3048)
			(stroke
				(width 0.1)
				(type default)
			)
			(layer "B.Fab")
		)
		(fp_line
			(start -0.67945 -0.3048)
			(end -0.67945 0.3048)
			(stroke
				(width 0.1)
				(type default)
			)
			(layer "B.Fab")
		)
		(pad "1" smd circle
			(at 0.40005 0)
			(size 0 0)
			(layers "B.Cu" "B.Mask" "B.Paste")
			(net "PWRGD_PVDD11_S3_P1")
		)
		(pad "2" smd circle
			(at -0.40005 0)
			(size 0 0)
			(layers "B.Cu" "B.Mask" "B.Paste")
			(net "PWRGD_PVDD11_S3_P1_R")
		)
	)
	(footprint ""
		(layer "B.Cu")
		(at 230.65105 -223.041972 -90)
		(property "Reference" "U2"
			(at 0.982218 2.852674 270)
			(unlocked yes)
			(layer "B.SilkS")
			(effects
				(font
					(size 0.7874 0.5842)
					(thickness 0.1524)
				)
				(justify left mirror)
			)
		)
		(property "Value" ""
			(at 0 0 90)
			(layer "B.Fab")
			(effects
				(font
					(size 1.27 1.27)
				)
				(justify mirror)
			)
		)
		(duplicate_pad_numbers_are_jumpers no)
		(fp_line
			(start -1.463548 1.549908)
			(end 1.463548 1.549908)
			(stroke
				(width 0.1524)
				(type default)
			)
			(layer "B.SilkS")
		)
		(fp_line
			(start 1.463548 1.549908)
			(end 1.463548 -1.549908)
			(stroke
				(width 0.1524)
				(type default)
			)
			(layer "B.SilkS")
		)
		(fp_line
			(start 0 -0.762)
			(end -0.762 -1.549908)
			(stroke
				(width 0.1524)
				(type default)
			)
			(layer "B.SilkS")
		)
		(fp_line
			(start -1.463548 -1.549908)
			(end -1.463548 1.549908)
			(stroke
				(width 0.1524)
				(type default)
			)
			(layer "B.SilkS")
		)
		(fp_line
			(start -0.762 -1.549908)
			(end -1.463548 -1.549908)
			(stroke
				(width 0.1524)
				(type default)
			)
			(layer "B.SilkS")
		)
		(fp_line
			(start 0.787908 -1.549908)
			(end 0 -0.762)
			(stroke
				(width 0.1524)
				(type default)
			)
			(layer "B.SilkS")
		)
		(fp_line
			(start 1.463548 -1.549908)
			(end 0.787908 -1.549908)
			(stroke
				(width 0.1524)
				(type default)
			)
			(layer "B.SilkS")
		)
		(fp_poly
			(pts
				(xy 3.780282 -1.017524) (xy 3.160522 -1.327404) (xy 3.780282 -1.637284)
			)
			(stroke
				(width 0)
				(type default)
			)
			(fill yes)
			(layer "B.SilkS")
		)
		(fp_line
			(start -1.549908 1.549908)
			(end 1.549908 1.549908)
			(stroke
				(width 0.1)
				(type default)
			)
			(layer "B.Fab")
		)
		(fp_line
			(start 1.549908 1.549908)
			(end 1.549908 -1.549908)
			(stroke
				(width 0.1)
				(type default)
			)
			(layer "B.Fab")
		)
		(fp_line
			(start -1.549908 -1.549908)
			(end -1.549908 1.549908)
			(stroke
				(width 0.1)
				(type default)
			)
			(layer "B.Fab")
		)
		(fp_line
			(start 1.549908 -1.549908)
			(end -1.549908 -1.549908)
			(stroke
				(width 0.1)
				(type default)
			)
			(layer "B.Fab")
		)
		(fp_poly
			(pts
				(xy 3.4798 -1.359916) (xy 2.86004 -1.050036) (xy 3.4798 -0.740156)
			)
			(stroke
				(width 0)
				(type default)
			)
			(fill yes)
			(layer "B.Fab")
		)
		(pad "1" smd rect
			(at 2.175002 -1.050036)
			(size 0.6096 1.1684)
			(layers "B.Cu" "B.Mask" "B.Paste")
			(net "PVDD11_S3_P0")
		)
		(pad "2" smd rect
			(at 2.175002 -0.32512)
			(size 0.4318 1.1684)
			(layers "B.Cu" "B.Mask" "B.Paste")
			(net "SMB_CPU0_CPU1_APML_BUF2_SCL_R1")
		)
		(pad "3" smd rect
			(at 2.175002 0.32512)
			(size 0.4318 1.1684)
			(layers "B.Cu" "B.Mask" "B.Paste")
			(net "SMB_CPU0_CPU1_APML_BUF2_SDA_R1")
		)
		(pad "4" smd rect
			(at 2.175002 1.050036)
			(size 0.6096 1.1684)
			(layers "B.Cu" "B.Mask" "B.Paste")
			(net "GND")
		)
		(pad "5" smd rect
			(at -2.175002 1.050036)
			(size 0.6096 1.1684)
			(layers "B.Cu" "B.Mask" "B.Paste")
			(net "PU_U2_EN")
		)
		(pad "6" smd rect
			(at -2.175002 0.32512)
			(size 0.4318 1.1684)
			(layers "B.Cu" "B.Mask" "B.Paste")
			(net "SMB_CPU0_CPU1_APML_BUF2_SDA")
		)
		(pad "7" smd rect
			(at -2.175002 -0.32512)
			(size 0.4318 1.1684)
			(layers "B.Cu" "B.Mask" "B.Paste")
			(net "SMB_CPU0_CPU1_APML_BUF2_SCL")
		)
		(pad "8" smd rect
			(at -2.175002 -1.050036)
			(size 0.6096 1.1684)
			(layers "B.Cu" "B.Mask" "B.Paste")
			(net "P3V3_AUX")
		)
	)
	(footprint ""
		(layer "B.Cu")
		(at 102.811834 -249.368564 180)
		(property "Reference" "C2343"
			(at 0 0 0)
			(layer "B.SilkS")
			(hide yes)
			(effects
				(font
					(size 1.27 1.27)
				)
				(justify mirror)
			)
		)
		(property "Value" ""
			(at 0 0 0)
			(layer "B.Fab")
			(effects
				(font
					(size 1.27 1.27)
				)
				(justify mirror)
			)
		)
		(duplicate_pad_numbers_are_jumpers no)
		(fp_line
			(start 0.7874 0.4064)
			(end 0.7874 -0.4064)
			(stroke
				(width 0.1524)
				(type default)
			)
			(layer "B.SilkS")
		)
		(fp_line
			(start 0.7874 -0.4064)
			(end -0.7874 -0.4064)
			(stroke
				(width 0.1524)
				(type default)
			)
			(layer "B.SilkS")
		)
		(fp_line
			(start -0.7874 0.4064)
			(end 0.7874 0.4064)
			(stroke
				(width 0.1524)
				(type default)
			)
			(layer "B.SilkS")
		)
		(fp_line
			(start -0.7874 -0.4064)
			(end -0.7874 0.4064)
			(stroke
				(width 0.1524)
				(type default)
			)
			(layer "B.SilkS")
		)
		(fp_line
			(start 0.67945 0.3048)
			(end 0.67945 -0.305054)
			(stroke
				(width 0.1)
				(type default)
			)
			(layer "B.Fab")
		)
		(fp_line
			(start 0.67945 -0.305054)
			(end 0.12065 -0.305054)
			(stroke
				(width 0.1)
				(type default)
			)
			(layer "B.Fab")
		)
		(fp_line
			(start 0.12065 0.3048)
			(end 0.67945 0.3048)
			(stroke
				(width 0.1)
				(type default)
			)
			(layer "B.Fab")
		)
		(fp_line
			(start 0.12065 0.2794)
			(end 0.12065 0.3048)
			(stroke
				(width 0.1)
				(type default)
			)
			(layer "B.Fab")
		)
		(fp_line
			(start 0.12065 -0.2794)
			(end -0.12065 -0.2794)
			(stroke
				(width 0.1)
				(type default)
			)
			(layer "B.Fab")
		)
		(fp_line
			(start 0.12065 -0.305054)
			(end 0.12065 -0.2794)
			(stroke
				(width 0.1)
				(type default)
			)
			(layer "B.Fab")
		)
		(fp_line
			(start -0.120396 0.3048)
			(end -0.120396 0.2794)
			(stroke
				(width 0.1)
				(type default)
			)
			(layer "B.Fab")
		)
		(fp_line
			(start -0.120396 0.2794)
			(end 0.12065 0.2794)
			(stroke
				(width 0.1)
				(type default)
			)
			(layer "B.Fab")
		)
		(fp_line
			(start -0.12065 -0.2794)
			(end -0.12065 -0.3048)
			(stroke
				(width 0.1)
				(type default)
			)
			(layer "B.Fab")
		)
		(fp_line
			(start -0.12065 -0.3048)
			(end -0.67945 -0.3048)
			(stroke
				(width 0.1)
				(type default)
			)
			(layer "B.Fab")
		)
		(fp_line
			(start -0.67945 0.3048)
			(end -0.120396 0.3048)
			(stroke
				(width 0.1)
				(type default)
			)
			(layer "B.Fab")
		)
		(fp_line
			(start -0.67945 -0.3048)
			(end -0.67945 0.3048)
			(stroke
				(width 0.1)
				(type default)
			)
			(layer "B.Fab")
		)
		(pad "1" smd circle
			(at 0.40005 0)
			(size 0 0)
			(layers "B.Cu" "B.Mask" "B.Paste")
			(net "PVDDCR_CPU0_P1")
		)
		(pad "2" smd circle
			(at -0.40005 0)
			(size 0 0)
			(layers "B.Cu" "B.Mask" "B.Paste")
			(net "GND")
		)
	)
)
